# T6G (Grand Teton) — schematic netlist excerpt (pin names and nets, part order shuffled) for the footprints in the layout excerpt that follows; sources: Cadence DE-HDL packaged netlist, KiCad conversion of 04192023_DAF0TMB3IC0_F0TG_MB_C_brd_V02_OCP.brd

C1754  Q_CAP  0.1UF 25V 10% X7R  pkg 0402  page 127 : A = FM_SWB_BIC_READY_ISO_N ; B = GND
R317  Q_RES  1K 1% CHIP  pkg 0402LF  page 250 : A = PCA9548_PCIE3_ADDR2 ; B = GND

(kicad_pcb
	(version 20260206)
	(generator "pcbnew")
	(generator_version "10.0")
	(general
		(thickness 1.6)
		(legacy_teardrops no)
	)
	(paper "A4")
	(title_block
		(title "04192023_DAF0TMB3IC0_F0TG_MB_C_brd_V02_OCP.brd")
		(comment 1 "Grand Teton / footprints 4490-4491 of 8354")
	)
	(layers
		(0 "F.Cu" signal "TOP")
		(4 "In1.Cu" signal "GND")
		(6 "In2.Cu" signal "IN1")
		(8 "In3.Cu" signal "GND1")
		(10 "In4.Cu" signal "IN2")
		(12 "In5.Cu" signal "GND2")
		(14 "In6.Cu" signal "IN3")
		(16 "In7.Cu" signal "GND3")
		(18 "In8.Cu" signal "VCC")
		(20 "In9.Cu" signal "VCC1")
		(22 "In10.Cu" signal "GND4")
		(24 "In11.Cu" signal "IN4")
		(26 "In12.Cu" signal "GND5")
		(28 "In13.Cu" signal "IN5")
		(30 "In14.Cu" signal "GND6")
		(32 "In15.Cu" signal "IN6")
		(34 "In16.Cu" signal "GND7")
		(2 "B.Cu" signal "BOTTOM")
		(9 "F.Adhes" user "F.Adhesive")
		(11 "B.Adhes" user "B.Adhesive")
		(13 "F.Paste" user "Package Geometry/Pastemask Top")
		(15 "B.Paste" user "Package Geometry/Pastemask Bottom")
		(5 "F.SilkS" user "Ref Des/Silkscreen Top")
		(7 "B.SilkS" user "Ref Des/Silkscreen Bottom")
		(1 "F.Mask" user "Board Geometry/Soldermask Top")
		(3 "B.Mask" user "Board Geometry/Soldermask Bottom")
		(17 "Dwgs.User" user "User.Drawings")
		(19 "Cmts.User" user "User.Comments")
		(21 "Eco1.User" user "User.Eco1")
		(23 "Eco2.User" user "User.Eco2")
		(25 "Edge.Cuts" user "Board Geometry/Outline")
		(27 "Margin" user)
		(31 "F.CrtYd" user "Package Geometry/Place Bound Top")
		(29 "B.CrtYd" user "Package Geometry/Place Bound Bottom")
		(35 "F.Fab" user "Ref Des/Assembly Top")
		(33 "B.Fab" user "Ref Des/Assembly Bottom")
	)
	(footprint ""
		(layer "F.Cu")
		(at 429.136302 -434.386736 -90)
		(property "Reference" "C1754"
			(at 0 0 270)
			(layer "F.SilkS")
			(hide yes)
			(effects
				(font
					(size 1.27 1.27)
				)
			)
		)
		(property "Value" ""
			(at 0 0 270)
			(layer "F.Fab")
			(effects
				(font
					(size 1.27 1.27)
				)
			)
		)
		(duplicate_pad_numbers_are_jumpers no)
		(fp_line
			(start -0.7874 0.4064)
			(end -0.7874 -0.4064)
			(stroke
				(width 0.1524)
				(type default)
			)
			(layer "F.SilkS")
		)
		(fp_line
			(start 0.7874 0.4064)
			(end -0.7874 0.4064)
			(stroke
				(width 0.1524)
				(type default)
			)
			(layer "F.SilkS")
		)
		(fp_line
			(start -0.7874 -0.4064)
			(end 0.7874 -0.4064)
			(stroke
				(width 0.1524)
				(type default)
			)
			(layer "F.SilkS")
		)
		(fp_line
			(start 0.7874 -0.4064)
			(end 0.7874 0.4064)
			(stroke
				(width 0.1524)
				(type default)
			)
			(layer "F.SilkS")
		)
		(fp_line
			(start -0.67945 0.3048)
			(end -0.67945 -0.305054)
			(stroke
				(width 0.1)
				(type default)
			)
			(layer "F.Fab")
		)
		(fp_line
			(start -0.12065 0.3048)
			(end -0.67945 0.3048)
			(stroke
				(width 0.1)
				(type default)
			)
			(layer "F.Fab")
		)
		(fp_line
			(start 0.120396 0.3048)
			(end 0.120396 0.2794)
			(stroke
				(width 0.1)
				(type default)
			)
			(layer "F.Fab")
		)
		(fp_line
			(start 0.67945 0.3048)
			(end 0.120396 0.3048)
			(stroke
				(width 0.1)
				(type default)
			)
			(layer "F.Fab")
		)
		(fp_line
			(start -0.12065 0.2794)
			(end -0.12065 0.3048)
			(stroke
				(width 0.1)
				(type default)
			)
			(layer "F.Fab")
		)
		(fp_line
			(start 0.120396 0.2794)
			(end -0.12065 0.2794)
			(stroke
				(width 0.1)
				(type default)
			)
			(layer "F.Fab")
		)
		(fp_line
			(start -0.12065 -0.2794)
			(end 0.12065 -0.2794)
			(stroke
				(width 0.1)
				(type default)
			)
			(layer "F.Fab")
		)
		(fp_line
			(start 0.12065 -0.2794)
			(end 0.12065 -0.3048)
			(stroke
				(width 0.1)
				(type default)
			)
			(layer "F.Fab")
		)
		(fp_line
			(start 0.12065 -0.3048)
			(end 0.67945 -0.3048)
			(stroke
				(width 0.1)
				(type default)
			)
			(layer "F.Fab")
		)
		(fp_line
			(start 0.67945 -0.3048)
			(end 0.67945 0.3048)
			(stroke
				(width 0.1)
				(type default)
			)
			(layer "F.Fab")
		)
		(fp_line
			(start -0.67945 -0.305054)
			(end -0.12065 -0.305054)
			(stroke
				(width 0.1)
				(type default)
			)
			(layer "F.Fab")
		)
		(fp_line
			(start -0.12065 -0.305054)
			(end -0.12065 -0.2794)
			(stroke
				(width 0.1)
				(type default)
			)
			(layer "F.Fab")
		)
		(pad "1" smd circle
			(at -0.40005 0 270)
			(size 0 0)
			(layers "F.Cu" "F.Mask" "F.Paste")
			(net "FM_SWB_BIC_READY_ISO_N")
		)
		(pad "2" smd circle
			(at 0.40005 0 270)
			(size 0 0)
			(layers "F.Cu" "F.Mask" "F.Paste")
			(net "GND")
		)
	)
	(footprint ""
		(layer "F.Cu")
		(at 294.421052 -122.349514)
		(property "Reference" "R317"
			(at 0 0 0)
			(layer "F.SilkS")
			(hide yes)
			(effects
				(font
					(size 1.27 1.27)
				)
			)
		)
		(property "Value" ""
			(at 0 0 0)
			(layer "F.Fab")
			(effects
				(font
					(size 1.27 1.27)
				)
			)
		)
		(duplicate_pad_numbers_are_jumpers no)
		(fp_line
			(start -0.7874 -0.4064)
			(end 0.7874 -0.4064)
			(stroke
				(width 0.1524)
				(type default)
			)
			(layer "F.SilkS")
		)
		(fp_line
			(start -0.7874 0.4064)
			(end -0.7874 -0.4064)
			(stroke
				(width 0.1524)
				(type default)
			)
			(layer "F.SilkS")
		)
		(fp_line
			(start 0.7874 -0.4064)
			(end 0.7874 0.4064)
			(stroke
				(width 0.1524)
				(type default)
			)
			(layer "F.SilkS")
		)
		(fp_line
			(start 0.7874 0.4064)
			(end -0.7874 0.4064)
			(stroke
				(width 0.1524)
				(type default)
			)
			(layer "F.SilkS")
		)
		(fp_line
			(start -0.67945 -0.305054)
			(end -0.12065 -0.305054)
			(stroke
				(width 0.1)
				(type default)
			)
			(layer "F.Fab")
		)
		(fp_line
			(start -0.67945 0.3048)
			(end -0.67945 -0.305054)
			(stroke
				(width 0.1)
				(type default)
			)
			(layer "F.Fab")
		)
		(fp_line
			(start -0.12065 -0.305054)
			(end -0.12065 -0.2794)
			(stroke
				(width 0.1)
				(type default)
			)
			(layer "F.Fab")
		)
		(fp_line
			(start -0.12065 -0.2794)
			(end 0.12065 -0.2794)
			(stroke
				(width 0.1)
				(type default)
			)
			(layer "F.Fab")
		)
		(fp_line
			(start -0.12065 0.2794)
			(end -0.12065 0.3048)
			(stroke
				(width 0.1)
				(type default)
			)
			(layer "F.Fab")
		)
		(fp_line
			(start -0.12065 0.3048)
			(end -0.67945 0.3048)
			(stroke
				(width 0.1)
				(type default)
			)
			(layer "F.Fab")
		)
		(fp_line
			(start 0.120396 0.2794)
			(end -0.12065 0.2794)
			(stroke
				(width 0.1)
				(type default)
			)
			(layer "F.Fab")
		)
		(fp_line
			(start 0.120396 0.3048)
			(end 0.120396 0.2794)
			(stroke
				(width 0.1)
				(type default)
			)
			(layer "F.Fab")
		)
		(fp_line
			(start 0.12065 -0.3048)
			(end 0.67945 -0.3048)
			(stroke
				(width 0.1)
				(type default)
			)
			(layer "F.Fab")
		)
		(fp_line
			(start 0.12065 -0.2794)
			(end 0.12065 -0.3048)
			(stroke
				(width 0.1)
				(type default)
			)
			(layer "F.Fab")
		)
		(fp_line
			(start 0.67945 -0.3048)
			(end 0.67945 0.3048)
			(stroke
				(width 0.1)
				(type default)
			)
			(layer "F.Fab")
		)
		(fp_line
			(start 0.67945 0.3048)
			(end 0.120396 0.3048)
			(stroke
				(width 0.1)
				(type default)
			)
			(layer "F.Fab")
		)
		(pad "1" smd circle
			(at -0.40005 0)
			(size 0 0)
			(layers "F.Cu" "F.Mask" "F.Paste")
			(net "PCA9548_PCIE3_ADDR2")
		)
		(pad "2" smd circle
			(at 0.40005 0)
			(size 0 0)
			(layers "F.Cu" "F.Mask" "F.Paste")
			(net "GND")
		)
	)
)
